(kicad_pcb
	(version 20260206)
	(generator "pcbnew")
	(generator_version "10.0")
	(general
		(thickness 1.6)
		(legacy_teardrops no)
	)
	(paper "A4")
	(title_block
		(title "03242023_DA0F0TMBIJ0_F0T_Motherboard_J_brd_V01_OCP.brd")
		(comment 1 "Grand Teton / footprints 4565-4570 of 6105")
	)
	(layers
		(0 "F.Cu" signal "TOP")
		(4 "In1.Cu" signal "GND")
		(6 "In2.Cu" signal "IN1")
		(8 "In3.Cu" signal "GND1")
		(10 "In4.Cu" signal "IN2")
		(12 "In5.Cu" signal "GND2")
		(14 "In6.Cu" signal "IN3")
		(16 "In7.Cu" signal "GND3")
		(18 "In8.Cu" signal "VCC")
		(20 "In9.Cu" signal "VCC1")
		(22 "In10.Cu" signal "GND4")
		(24 "In11.Cu" signal "IN4")
		(26 "In12.Cu" signal "GND5")
		(28 "In13.Cu" signal "IN5")
		(30 "In14.Cu" signal "GND6")
		(32 "In15.Cu" signal "IN6")
		(34 "In16.Cu" signal "GND7")
		(2 "B.Cu" signal "BOTTOM")
		(9 "F.Adhes" user "F.Adhesive")
		(11 "B.Adhes" user "B.Adhesive")
		(13 "F.Paste" user "Package Geometry/Pastemask Top")
		(15 "B.Paste" user "Package Geometry/Pastemask Bottom")
		(5 "F.SilkS" user "Ref Des/Silkscreen Top")
		(7 "B.SilkS" user "Ref Des/Silkscreen Bottom")
		(1 "F.Mask" user "Board Geometry/Soldermask Top")
		(3 "B.Mask" user "Board Geometry/Soldermask Bottom")
		(17 "Dwgs.User" user "User.Drawings")
		(19 "Cmts.User" user "User.Comments")
		(21 "Eco1.User" user "User.Eco1")
		(23 "Eco2.User" user "User.Eco2")
		(25 "Edge.Cuts" user "Board Geometry/Outline")
		(27 "Margin" user)
		(31 "F.CrtYd" user "Package Geometry/Place Bound Top")
		(29 "B.CrtYd" user "Package Geometry/Place Bound Bottom")
		(35 "F.Fab" user "Ref Des/Assembly Top")
		(33 "B.Fab" user "Ref Des/Assembly Bottom")
	)
	(footprint ""
		(layer "B.Cu")
		(at 122.157744 -354.189538)
		(property "Reference" "R2374"
			(at 0 0 0)
			(layer "B.SilkS")
			(hide yes)
			(effects
				(font
					(size 1.27 1.27)
				)
				(justify mirror)
			)
		)
		(property "Value" ""
			(at 0 0 0)
			(layer "B.Fab")
			(effects
				(font
					(size 1.27 1.27)
				)
				(justify mirror)
			)
		)
		(duplicate_pad_numbers_are_jumpers no)
		(fp_line
			(start -0.7874 -0.4064)
			(end -0.7874 0.4064)
			(stroke
				(width 0.1524)
				(type default)
			)
			(layer "B.SilkS")
		)
		(fp_line
			(start -0.7874 0.4064)
			(end 0.7874 0.4064)
			(stroke
				(width 0.1524)
				(type default)
			)
			(layer "B.SilkS")
		)
		(fp_line
			(start 0.7874 -0.4064)
			(end -0.7874 -0.4064)
			(stroke
				(width 0.1524)
				(type default)
			)
			(layer "B.SilkS")
		)
		(fp_line
			(start 0.7874 0.4064)
			(end 0.7874 -0.4064)
			(stroke
				(width 0.1524)
				(type default)
			)
			(layer "B.SilkS")
		)
		(fp_line
			(start -0.67945 -0.3048)
			(end -0.67945 0.3048)
			(stroke
				(width 0.1)
				(type default)
			)
			(layer "B.Fab")
		)
		(fp_line
			(start -0.67945 0.3048)
			(end -0.120396 0.3048)
			(stroke
				(width 0.1)
				(type default)
			)
			(layer "B.Fab")
		)
		(fp_line
			(start -0.12065 -0.3048)
			(end -0.67945 -0.3048)
			(stroke
				(width 0.1)
				(type default)
			)
			(layer "B.Fab")
		)
		(fp_line
			(start -0.12065 -0.2794)
			(end -0.12065 -0.3048)
			(stroke
				(width 0.1)
				(type default)
			)
			(layer "B.Fab")
		)
		(fp_line
			(start -0.120396 0.2794)
			(end 0.12065 0.2794)
			(stroke
				(width 0.1)
				(type default)
			)
			(layer "B.Fab")
		)
		(fp_line
			(start -0.120396 0.3048)
			(end -0.120396 0.2794)
			(stroke
				(width 0.1)
				(type default)
			)
			(layer "B.Fab")
		)
		(fp_line
			(start 0.12065 -0.305054)
			(end 0.12065 -0.2794)
			(stroke
				(width 0.1)
				(type default)
			)
			(layer "B.Fab")
		)
		(fp_line
			(start 0.12065 -0.2794)
			(end -0.12065 -0.2794)
			(stroke
				(width 0.1)
				(type default)
			)
			(layer "B.Fab")
		)
		(fp_line
			(start 0.12065 0.2794)
			(end 0.12065 0.3048)
			(stroke
				(width 0.1)
				(type default)
			)
			(layer "B.Fab")
		)
		(fp_line
			(start 0.12065 0.3048)
			(end 0.67945 0.3048)
			(stroke
				(width 0.1)
				(type default)
			)
			(layer "B.Fab")
		)
		(fp_line
			(start 0.67945 -0.305054)
			(end 0.12065 -0.305054)
			(stroke
				(width 0.1)
				(type default)
			)
			(layer "B.Fab")
		)
		(fp_line
			(start 0.67945 0.3048)
			(end 0.67945 -0.305054)
			(stroke
				(width 0.1)
				(type default)
			)
			(layer "B.Fab")
		)
		(pad "1" smd circle
			(at 0.40005 0 180)
			(size 0 0)
			(layers "B.Cu" "B.Mask" "B.Paste")
			(net "FM_PVPP_HBM_CPU1_EN")
		)
		(pad "2" smd circle
			(at -0.40005 0 180)
			(size 0 0)
			(layers "B.Cu" "B.Mask" "B.Paste")
			(net "GND")
		)
	)
	(footprint ""
		(layer "B.Cu")
		(at 258.953 -100.167948)
		(property "Reference" "C115"
			(at 0 0 0)
			(layer "B.SilkS")
			(hide yes)
			(effects
				(font
					(size 1.27 1.27)
				)
				(justify mirror)
			)
		)
		(property "Value" ""
			(at 0 0 0)
			(layer "B.Fab")
			(effects
				(font
					(size 1.27 1.27)
				)
				(justify mirror)
			)
		)
		(duplicate_pad_numbers_are_jumpers no)
		(fp_line
			(start -0.7874 -0.4064)
			(end -0.7874 0.4064)
			(stroke
				(width 0.1524)
				(type default)
			)
			(layer "B.SilkS")
		)
		(fp_line
			(start -0.7874 0.4064)
			(end 0.7874 0.4064)
			(stroke
				(width 0.1524)
				(type default)
			)
			(layer "B.SilkS")
		)
		(fp_line
			(start 0.7874 -0.4064)
			(end -0.7874 -0.4064)
			(stroke
				(width 0.1524)
				(type default)
			)
			(layer "B.SilkS")
		)
		(fp_line
			(start 0.7874 0.4064)
			(end 0.7874 -0.4064)
			(stroke
				(width 0.1524)
				(type default)
			)
			(layer "B.SilkS")
		)
		(fp_line
			(start -0.67945 -0.3048)
			(end -0.67945 0.3048)
			(stroke
				(width 0.1)
				(type default)
			)
			(layer "B.Fab")
		)
		(fp_line
			(start -0.67945 0.3048)
			(end -0.120396 0.3048)
			(stroke
				(width 0.1)
				(type default)
			)
			(layer "B.Fab")
		)
		(fp_line
			(start -0.12065 -0.3048)
			(end -0.67945 -0.3048)
			(stroke
				(width 0.1)
				(type default)
			)
			(layer "B.Fab")
		)
		(fp_line
			(start -0.12065 -0.2794)
			(end -0.12065 -0.3048)
			(stroke
				(width 0.1)
				(type default)
			)
			(layer "B.Fab")
		)
		(fp_line
			(start -0.120396 0.2794)
			(end 0.12065 0.2794)
			(stroke
				(width 0.1)
				(type default)
			)
			(layer "B.Fab")
		)
		(fp_line
			(start -0.120396 0.3048)
			(end -0.120396 0.2794)
			(stroke
				(width 0.1)
				(type default)
			)
			(layer "B.Fab")
		)
		(fp_line
			(start 0.12065 -0.305054)
			(end 0.12065 -0.2794)
			(stroke
				(width 0.1)
				(type default)
			)
			(layer "B.Fab")
		)
		(fp_line
			(start 0.12065 -0.2794)
			(end -0.12065 -0.2794)
			(stroke
				(width 0.1)
				(type default)
			)
			(layer "B.Fab")
		)
		(fp_line
			(start 0.12065 0.2794)
			(end 0.12065 0.3048)
			(stroke
				(width 0.1)
				(type default)
			)
			(layer "B.Fab")
		)
		(fp_line
			(start 0.12065 0.3048)
			(end 0.67945 0.3048)
			(stroke
				(width 0.1)
				(type default)
			)
			(layer "B.Fab")
		)
		(fp_line
			(start 0.67945 -0.305054)
			(end 0.12065 -0.305054)
			(stroke
				(width 0.1)
				(type default)
			)
			(layer "B.Fab")
		)
		(fp_line
			(start 0.67945 0.3048)
			(end 0.67945 -0.305054)
			(stroke
				(width 0.1)
				(type default)
			)
			(layer "B.Fab")
		)
		(pad "1" smd circle
			(at 0.40005 0 180)
			(size 0 0)
			(layers "B.Cu" "B.Mask" "B.Paste")
			(net "P3V3_AUX_CLK_GEN_VDDMXCK_CK440")
		)
		(pad "2" smd circle
			(at -0.40005 0 180)
			(size 0 0)
			(layers "B.Cu" "B.Mask" "B.Paste")
			(net "GND")
		)
	)
	(footprint ""
		(layer "B.Cu")
		(at 150.900638 -13.762228 90)
		(property "Reference" "R2418"
			(at 0 0 90)
			(layer "B.SilkS")
			(hide yes)
			(effects
				(font
					(size 1.27 1.27)
				)
				(justify mirror)
			)
		)
		(property "Value" ""
			(at 0 0 90)
			(layer "B.Fab")
			(effects
				(font
					(size 1.27 1.27)
				)
				(justify mirror)
			)
		)
		(duplicate_pad_numbers_are_jumpers no)
		(fp_line
			(start 0.7874 -0.4064)
			(end -0.7874 -0.4064)
			(stroke
				(width 0.1524)
				(type default)
			)
			(layer "B.SilkS")
		)
		(fp_line
			(start -0.7874 -0.4064)
			(end -0.7874 0.4064)
			(stroke
				(width 0.1524)
				(type default)
			)
			(layer "B.SilkS")
		)
		(fp_line
			(start 0.7874 0.4064)
			(end 0.7874 -0.4064)
			(stroke
				(width 0.1524)
				(type default)
			)
			(layer "B.SilkS")
		)
		(fp_line
			(start -0.7874 0.4064)
			(end 0.7874 0.4064)
			(stroke
				(width 0.1524)
				(type default)
			)
			(layer "B.SilkS")
		)
		(fp_line
			(start 0.67945 -0.305054)
			(end 0.12065 -0.305054)
			(stroke
				(width 0.1)
				(type default)
			)
			(layer "B.Fab")
		)
		(fp_line
			(start 0.12065 -0.305054)
			(end 0.12065 -0.2794)
			(stroke
				(width 0.1)
				(type default)
			)
			(layer "B.Fab")
		)
		(fp_line
			(start -0.12065 -0.3048)
			(end -0.67945 -0.3048)
			(stroke
				(width 0.1)
				(type default)
			)
			(layer "B.Fab")
		)
		(fp_line
			(start -0.67945 -0.3048)
			(end -0.67945 0.3048)
			(stroke
				(width 0.1)
				(type default)
			)
			(layer "B.Fab")
		)
		(fp_line
			(start 0.12065 -0.2794)
			(end -0.12065 -0.2794)
			(stroke
				(width 0.1)
				(type default)
			)
			(layer "B.Fab")
		)
		(fp_line
			(start -0.12065 -0.2794)
			(end -0.12065 -0.3048)
			(stroke
				(width 0.1)
				(type default)
			)
			(layer "B.Fab")
		)
		(fp_line
			(start 0.12065 0.2794)
			(end 0.12065 0.3048)
			(stroke
				(width 0.1)
				(type default)
			)
			(layer "B.Fab")
		)
		(fp_line
			(start -0.120396 0.2794)
			(end 0.12065 0.2794)
			(stroke
				(width 0.1)
				(type default)
			)
			(layer "B.Fab")
		)
		(fp_line
			(start 0.67945 0.3048)
			(end 0.67945 -0.305054)
			(stroke
				(width 0.1)
				(type default)
			)
			(layer "B.Fab")
		)
		(fp_line
			(start 0.12065 0.3048)
			(end 0.67945 0.3048)
			(stroke
				(width 0.1)
				(type default)
			)
			(layer "B.Fab")
		)
		(fp_line
			(start -0.120396 0.3048)
			(end -0.120396 0.2794)
			(stroke
				(width 0.1)
				(type default)
			)
			(layer "B.Fab")
		)
		(fp_line
			(start -0.67945 0.3048)
			(end -0.120396 0.3048)
			(stroke
				(width 0.1)
				(type default)
			)
			(layer "B.Fab")
		)
		(pad "1" smd circle
			(at 0.40005 0 270)
			(size 0 0)
			(layers "B.Cu" "B.Mask" "B.Paste")
			(net "SMB_S3M_CPU_3V3AUX_SDA")
		)
		(pad "2" smd circle
			(at -0.40005 0 270)
			(size 0 0)
			(layers "B.Cu" "B.Mask" "B.Paste")
			(net "SMB_S3M_CPU_3V3AUX_SDA_R0")
		)
	)
	(footprint ""
		(layer "B.Cu")
		(at 404.011892 -54.754272 180)
		(property "Reference" "C548"
			(at 0 0 0)
			(layer "B.SilkS")
			(hide yes)
			(effects
				(font
					(size 1.27 1.27)
				)
				(justify mirror)
			)
		)
		(property "Value" ""
			(at 0 0 0)
			(layer "B.Fab")
			(effects
				(font
					(size 1.27 1.27)
				)
				(justify mirror)
			)
		)
		(duplicate_pad_numbers_are_jumpers no)
		(fp_line
			(start 0.7874 0.4064)
			(end 0.7874 -0.4064)
			(stroke
				(width 0.1524)
				(type default)
			)
			(layer "B.SilkS")
		)
		(fp_line
			(start 0.7874 -0.4064)
			(end -0.7874 -0.4064)
			(stroke
				(width 0.1524)
				(type default)
			)
			(layer "B.SilkS")
		)
		(fp_line
			(start -0.7874 0.4064)
			(end 0.7874 0.4064)
			(stroke
				(width 0.1524)
				(type default)
			)
			(layer "B.SilkS")
		)
		(fp_line
			(start -0.7874 -0.4064)
			(end -0.7874 0.4064)
			(stroke
				(width 0.1524)
				(type default)
			)
			(layer "B.SilkS")
		)
		(fp_line
			(start 0.67945 0.3048)
			(end 0.67945 -0.305054)
			(stroke
				(width 0.1)
				(type default)
			)
			(layer "B.Fab")
		)
		(fp_line
			(start 0.67945 -0.305054)
			(end 0.12065 -0.305054)
			(stroke
				(width 0.1)
				(type default)
			)
			(layer "B.Fab")
		)
		(fp_line
			(start 0.12065 0.3048)
			(end 0.67945 0.3048)
			(stroke
				(width 0.1)
				(type default)
			)
			(layer "B.Fab")
		)
		(fp_line
			(start 0.12065 0.2794)
			(end 0.12065 0.3048)
			(stroke
				(width 0.1)
				(type default)
			)
			(layer "B.Fab")
		)
		(fp_line
			(start 0.12065 -0.2794)
			(end -0.12065 -0.2794)
			(stroke
				(width 0.1)
				(type default)
			)
			(layer "B.Fab")
		)
		(fp_line
			(start 0.12065 -0.305054)
			(end 0.12065 -0.2794)
			(stroke
				(width 0.1)
				(type default)
			)
			(layer "B.Fab")
		)
		(fp_line
			(start -0.120396 0.3048)
			(end -0.120396 0.2794)
			(stroke
				(width 0.1)
				(type default)
			)
			(layer "B.Fab")
		)
		(fp_line
			(start -0.120396 0.2794)
			(end 0.12065 0.2794)
			(stroke
				(width 0.1)
				(type default)
			)
			(layer "B.Fab")
		)
		(fp_line
			(start -0.12065 -0.2794)
			(end -0.12065 -0.3048)
			(stroke
				(width 0.1)
				(type default)
			)
			(layer "B.Fab")
		)
		(fp_line
			(start -0.12065 -0.3048)
			(end -0.67945 -0.3048)
			(stroke
				(width 0.1)
				(type default)
			)
			(layer "B.Fab")
		)
		(fp_line
			(start -0.67945 0.3048)
			(end -0.120396 0.3048)
			(stroke
				(width 0.1)
				(type default)
			)
			(layer "B.Fab")
		)
		(fp_line
			(start -0.67945 -0.3048)
			(end -0.67945 0.3048)
			(stroke
				(width 0.1)
				(type default)
			)
			(layer "B.Fab")
		)
		(pad "1" smd circle
			(at 0.40005 0)
			(size 0 0)
			(layers "B.Cu" "B.Mask" "B.Paste")
			(net "JTAG_DBP_POWER_BTN_N")
		)
		(pad "2" smd circle
			(at -0.40005 0)
			(size 0 0)
			(layers "B.Cu" "B.Mask" "B.Paste")
			(net "GND")
		)
	)
	(footprint ""
		(layer "B.Cu")
		(at 116.40312 -259.53212 90)
		(property "Reference" "C450"
			(at 0 0 90)
			(layer "B.SilkS")
			(hide yes)
			(effects
				(font
					(size 1.27 1.27)
				)
				(justify mirror)
			)
		)
		(property "Value" ""
			(at 0 0 90)
			(layer "B.Fab")
			(effects
				(font
					(size 1.27 1.27)
				)
				(justify mirror)
			)
		)
		(duplicate_pad_numbers_are_jumpers no)
		(fp_line
			(start 1.524 -0.762)
			(end -1.524 -0.762)
			(stroke
				(width 0.1524)
				(type default)
			)
			(layer "B.SilkS")
		)
		(fp_line
			(start -1.524 -0.762)
			(end -1.524 0.762)
			(stroke
				(width 0.1524)
				(type default)
			)
			(layer "B.SilkS")
		)
		(fp_line
			(start 1.524 0.762)
			(end 1.524 -0.762)
			(stroke
				(width 0.1524)
				(type default)
			)
			(layer "B.SilkS")
		)
		(fp_line
			(start -1.524 0.762)
			(end 1.524 0.762)
			(stroke
				(width 0.1524)
				(type default)
			)
			(layer "B.SilkS")
		)
		(fp_line
			(start 1.1049 -0.724916)
			(end 1.1049 0.724916)
			(stroke
				(width 0.1)
				(type default)
			)
			(layer "B.Fab")
		)
		(fp_line
			(start -1.1049 -0.724916)
			(end 1.1049 -0.724916)
			(stroke
				(width 0.1)
				(type default)
			)
			(layer "B.Fab")
		)
		(fp_line
			(start 1.1049 0.724916)
			(end -1.1049 0.724916)
			(stroke
				(width 0.1)
				(type default)
			)
			(layer "B.Fab")
		)
		(fp_line
			(start -1.1049 0.724916)
			(end -1.1049 -0.724916)
			(stroke
				(width 0.1)
				(type default)
			)
			(layer "B.Fab")
		)
		(pad "1" smd rect
			(at 0.889 0 90)
			(size 1.016 1.27)
			(layers "B.Cu" "B.Mask" "B.Paste")
			(net "PVCCFA_EHV_FIVRA_CPU1")
		)
		(pad "2" smd rect
			(at -0.889 0 90)
			(size 1.016 1.27)
			(layers "B.Cu" "B.Mask" "B.Paste")
			(net "GND")
		)
	)
	(footprint ""
		(layer "B.Cu")
		(at 48.344328 -354.558854 -90)
		(property "Reference" "PR227"
			(at 0 0 90)
			(layer "B.SilkS")
			(hide yes)
			(effects
				(font
					(size 1.27 1.27)
				)
				(justify mirror)
			)
		)
		(property "Value" ""
			(at 0 0 90)
			(layer "B.Fab")
			(effects
				(font
					(size 1.27 1.27)
				)
				(justify mirror)
			)
		)
		(duplicate_pad_numbers_are_jumpers no)
		(fp_line
			(start -0.7874 0.4064)
			(end 0.7874 0.4064)
			(stroke
				(width 0.1524)
				(type default)
			)
			(layer "B.SilkS")
		)
		(fp_line
			(start 0.7874 0.4064)
			(end 0.7874 -0.4064)
			(stroke
				(width 0.1524)
				(type default)
			)
			(layer "B.SilkS")
		)
		(fp_line
			(start -0.7874 -0.4064)
			(end -0.7874 0.4064)
			(stroke
				(width 0.1524)
				(type default)
			)
			(layer "B.SilkS")
		)
		(fp_line
			(start 0.7874 -0.4064)
			(end -0.7874 -0.4064)
			(stroke
				(width 0.1524)
				(type default)
			)
			(layer "B.SilkS")
		)
		(fp_line
			(start -0.67945 0.3048)
			(end -0.120396 0.3048)
			(stroke
				(width 0.1)
				(type default)
			)
			(layer "B.Fab")
		)
		(fp_line
			(start -0.120396 0.3048)
			(end -0.120396 0.2794)
			(stroke
				(width 0.1)
				(type default)
			)
			(layer "B.Fab")
		)
		(fp_line
			(start 0.12065 0.3048)
			(end 0.67945 0.3048)
			(stroke
				(width 0.1)
				(type default)
			)
			(layer "B.Fab")
		)
		(fp_line
			(start 0.67945 0.3048)
			(end 0.67945 -0.305054)
			(stroke
				(width 0.1)
				(type default)
			)
			(layer "B.Fab")
		)
		(fp_line
			(start -0.120396 0.2794)
			(end 0.12065 0.2794)
			(stroke
				(width 0.1)
				(type default)
			)
			(layer "B.Fab")
		)
		(fp_line
			(start 0.12065 0.2794)
			(end 0.12065 0.3048)
			(stroke
				(width 0.1)
				(type default)
			)
			(layer "B.Fab")
		)
		(fp_line
			(start -0.12065 -0.2794)
			(end -0.12065 -0.3048)
			(stroke
				(width 0.1)
				(type default)
			)
			(layer "B.Fab")
		)
		(fp_line
			(start 0.12065 -0.2794)
			(end -0.12065 -0.2794)
			(stroke
				(width 0.1)
				(type default)
			)
			(layer "B.Fab")
		)
		(fp_line
			(start -0.67945 -0.3048)
			(end -0.67945 0.3048)
			(stroke
				(width 0.1)
				(type default)
			)
			(layer "B.Fab")
		)
		(fp_line
			(start -0.12065 -0.3048)
			(end -0.67945 -0.3048)
			(stroke
				(width 0.1)
				(type default)
			)
			(layer "B.Fab")
		)
		(fp_line
			(start 0.12065 -0.305054)
			(end 0.12065 -0.2794)
			(stroke
				(width 0.1)
				(type default)
			)
			(layer "B.Fab")
		)
		(fp_line
			(start 0.67945 -0.305054)
			(end 0.12065 -0.305054)
			(stroke
				(width 0.1)
				(type default)
			)
			(layer "B.Fab")
		)
		(pad "1" smd circle
			(at 0.40005 0 90)
			(size 0 0)
			(layers "B.Cu" "B.Mask" "B.Paste")
			(net "PVCCFA_EHV_FIVRA_CPU1_PVCC2")
		)
		(pad "2" smd circle
			(at -0.40005 0 90)
			(size 0 0)
			(layers "B.Cu" "B.Mask" "B.Paste")
			(net "PVCCFA_EHV_FIVRA_CPU1_VDD2")
		)
	)
)
